(kicad_pcb
	(version 20260206)
	(generator "pcbnew")
	(generator_version "10.0")
	(general
		(thickness 1.6)
		(legacy_teardrops no)
	)
	(paper "A4")
	(title_block
		(title "01162023_DA0F0TEBIF0_F0T_Expander_BD_F_brd_V02_OCP.brd")
		(comment 1 "Grand Teton / footprints 3733-3735 of 9728")
	)
	(layers
		(0 "F.Cu" signal "TOP")
		(4 "In1.Cu" signal "GND")
		(6 "In2.Cu" signal "VCC")
		(8 "In3.Cu" signal "VCC1")
		(10 "In4.Cu" signal "GND1")
		(12 "In5.Cu" signal "IN1")
		(14 "In6.Cu" signal "GND2")
		(16 "In7.Cu" signal "IN2")
		(18 "In8.Cu" signal "GND3")
		(20 "In9.Cu" signal "IN3")
		(22 "In10.Cu" signal "GND4")
		(24 "In11.Cu" signal "IN4")
		(26 "In12.Cu" signal "GND5")
		(28 "In13.Cu" signal "IN5")
		(30 "In14.Cu" signal "GND6")
		(32 "In15.Cu" signal "IN6")
		(34 "In16.Cu" signal "GND7")
		(2 "B.Cu" signal "BOTTOM")
		(9 "F.Adhes" user "F.Adhesive")
		(11 "B.Adhes" user "B.Adhesive")
		(13 "F.Paste" user "Package Geometry/Pastemask Top")
		(15 "B.Paste" user "Package Geometry/Pastemask Bottom")
		(5 "F.SilkS" user "Ref Des/Silkscreen Top")
		(7 "B.SilkS" user "Ref Des/Silkscreen Bottom")
		(1 "F.Mask" user "Board Geometry/Soldermask Top")
		(3 "B.Mask" user "Board Geometry/Soldermask Bottom")
		(17 "Dwgs.User" user "User.Drawings")
		(19 "Cmts.User" user "User.Comments")
		(21 "Eco1.User" user "User.Eco1")
		(23 "Eco2.User" user "User.Eco2")
		(25 "Edge.Cuts" user "Board Geometry/Outline")
		(27 "Margin" user)
		(31 "F.CrtYd" user "Package Geometry/Place Bound Top")
		(29 "B.CrtYd" user "Package Geometry/Place Bound Bottom")
		(35 "F.Fab" user "Ref Des/Assembly Top")
		(33 "B.Fab" user "Ref Des/Assembly Bottom")
	)
	(footprint ""
		(layer "F.Cu")
		(at 376.40514 -307.084984 45)
		(property "Reference" "R1418"
			(at 0 0 45)
			(layer "F.SilkS")
			(hide yes)
			(effects
				(font
					(size 1.27 1.27)
				)
			)
		)
		(property "Value" ""
			(at 0 0 45)
			(layer "F.Fab")
			(effects
				(font
					(size 1.27 1.27)
				)
			)
		)
		(duplicate_pad_numbers_are_jumpers no)
		(fp_line
			(start -0.787389 -0.406267)
			(end 0.787389 -0.406267)
			(stroke
				(width 0.1524)
				(type default)
			)
			(layer "F.SilkS")
		)
		(fp_line
			(start -0.787389 0.406267)
			(end -0.787389 -0.406267)
			(stroke
				(width 0.1524)
				(type default)
			)
			(layer "F.SilkS")
		)
		(fp_line
			(start 0.787389 -0.406267)
			(end 0.787389 0.406267)
			(stroke
				(width 0.1524)
				(type default)
			)
			(layer "F.SilkS")
		)
		(fp_line
			(start 0.787389 0.406267)
			(end -0.787389 0.406267)
			(stroke
				(width 0.1524)
				(type default)
			)
			(layer "F.SilkS")
		)
		(fp_line
			(start -0.679446 -0.305149)
			(end -0.120695 -0.304969)
			(stroke
				(width 0.1)
				(type default)
			)
			(layer "F.Fab")
		)
		(fp_line
			(start -0.120695 -0.304969)
			(end -0.120695 -0.279466)
			(stroke
				(width 0.1)
				(type default)
			)
			(layer "F.Fab")
		)
		(fp_line
			(start -0.120695 -0.279466)
			(end 0.120695 -0.279466)
			(stroke
				(width 0.1)
				(type default)
			)
			(layer "F.Fab")
		)
		(fp_line
			(start -0.679446 0.30479)
			(end -0.679446 -0.305149)
			(stroke
				(width 0.1)
				(type default)
			)
			(layer "F.Fab")
		)
		(fp_line
			(start 0.120515 -0.30479)
			(end 0.679446 -0.30479)
			(stroke
				(width 0.1)
				(type default)
			)
			(layer "F.Fab")
		)
		(fp_line
			(start 0.120695 -0.279466)
			(end 0.120515 -0.30479)
			(stroke
				(width 0.1)
				(type default)
			)
			(layer "F.Fab")
		)
		(fp_line
			(start -0.120695 0.279466)
			(end -0.120515 0.30479)
			(stroke
				(width 0.1)
				(type default)
			)
			(layer "F.Fab")
		)
		(fp_line
			(start -0.120515 0.30479)
			(end -0.679446 0.30479)
			(stroke
				(width 0.1)
				(type default)
			)
			(layer "F.Fab")
		)
		(fp_line
			(start 0.679446 -0.30479)
			(end 0.679446 0.30479)
			(stroke
				(width 0.1)
				(type default)
			)
			(layer "F.Fab")
		)
		(fp_line
			(start 0.120335 0.279466)
			(end -0.120695 0.279466)
			(stroke
				(width 0.1)
				(type default)
			)
			(layer "F.Fab")
		)
		(fp_line
			(start 0.120515 0.30479)
			(end 0.120335 0.279466)
			(stroke
				(width 0.1)
				(type default)
			)
			(layer "F.Fab")
		)
		(fp_line
			(start 0.679446 0.30479)
			(end 0.120515 0.30479)
			(stroke
				(width 0.1)
				(type default)
			)
			(layer "F.Fab")
		)
		(pad "1" smd circle
			(at -0.40005 0 45)
			(size 0 0)
			(layers "F.Cu" "F.Mask" "F.Paste")
			(net "GND")
		)
		(pad "2" smd circle
			(at 0.40005 0 45)
			(size 0 0)
			(layers "F.Cu" "F.Mask" "F.Paste")
			(net "PEX3_DBG_SEL0")
		)
	)
	(footprint ""
		(layer "F.Cu")
		(at 278.257 -388.8486 90)
		(property "Reference" "PU6601"
			(at -1.703578 2.51587 90)
			(unlocked yes)
			(layer "F.SilkS")
			(effects
				(font
					(size 0.7874 0.5842)
					(thickness 0.1524)
				)
				(justify left)
			)
		)
		(property "Value" ""
			(at 0 0 90)
			(layer "F.Fab")
			(effects
				(font
					(size 1.27 1.27)
				)
			)
		)
		(duplicate_pad_numbers_are_jumpers no)
		(fp_line
			(start 1.448308 -1.549908)
			(end 1.448308 1.549908)
			(stroke
				(width 0.1524)
				(type default)
			)
			(layer "F.SilkS")
		)
		(fp_line
			(start 0.774954 -1.549908)
			(end 1.448308 -1.549908)
			(stroke
				(width 0.1524)
				(type default)
			)
			(layer "F.SilkS")
		)
		(fp_line
			(start -0.774954 -1.549908)
			(end 0 -0.533908)
			(stroke
				(width 0.1524)
				(type default)
			)
			(layer "F.SilkS")
		)
		(fp_line
			(start -1.448308 -1.549908)
			(end -0.774954 -1.549908)
			(stroke
				(width 0.1524)
				(type default)
			)
			(layer "F.SilkS")
		)
		(fp_line
			(start 0 -0.533908)
			(end 0.774954 -1.549908)
			(stroke
				(width 0.1524)
				(type default)
			)
			(layer "F.SilkS")
		)
		(fp_line
			(start 1.448308 1.549908)
			(end -1.448308 1.549908)
			(stroke
				(width 0.1524)
				(type default)
			)
			(layer "F.SilkS")
		)
		(fp_line
			(start -1.448308 1.549908)
			(end -1.448308 -1.549908)
			(stroke
				(width 0.1524)
				(type default)
			)
			(layer "F.SilkS")
		)
		(fp_poly
			(pts
				(xy -1.549908 -1.549908) (xy -0.787908 -1.549908) (xy -0.787908 -1.880108) (xy -1.549908 -1.880108)
			)
			(stroke
				(width 0)
				(type default)
			)
			(fill yes)
			(layer "F.SilkS")
		)
		(fp_line
			(start 1.549908 -1.549908)
			(end 1.549908 1.549908)
			(stroke
				(width 0.1)
				(type default)
			)
			(layer "F.Fab")
		)
		(fp_line
			(start -1.549908 -1.549908)
			(end 1.549908 -1.549908)
			(stroke
				(width 0.1)
				(type default)
			)
			(layer "F.Fab")
		)
		(fp_line
			(start 1.549908 1.549908)
			(end -1.549908 1.549908)
			(stroke
				(width 0.1)
				(type default)
			)
			(layer "F.Fab")
		)
		(fp_line
			(start -1.549908 1.549908)
			(end -1.549908 -1.549908)
			(stroke
				(width 0.1)
				(type default)
			)
			(layer "F.Fab")
		)
		(fp_poly
			(pts
				(xy -1.549908 -1.549908) (xy -0.787908 -1.549908) (xy -0.787908 -1.880108) (xy -1.549908 -1.880108)
			)
			(stroke
				(width 0)
				(type default)
			)
			(fill yes)
			(layer "F.Fab")
		)
		(pad "1" smd rect
			(at -2.350008 -0.975106)
			(size 0.4318 1.4986)
			(layers "F.Cu" "F.Mask" "F.Paste")
			(net "P3V3_AUX")
		)
		(pad "2" smd rect
			(at -2.350008 -0.32512)
			(size 0.4318 1.4986)
			(layers "F.Cu" "F.Mask" "F.Paste")
			(net "LTC4282_TEMP_D+")
		)
		(pad "3" smd rect
			(at -2.350008 0.32512)
			(size 0.4318 1.4986)
			(layers "F.Cu" "F.Mask" "F.Paste")
			(net "LTC4282_TEMP_D-")
		)
		(pad "4" smd rect
			(at -2.350008 0.975106)
			(size 0.4318 1.4986)
			(layers "F.Cu" "F.Mask" "F.Paste")
			(net "LTC4282_T_CRIT_N")
		)
		(pad "5" smd rect
			(at 2.350008 0.975106)
			(size 0.4318 1.4986)
			(layers "F.Cu" "F.Mask" "F.Paste")
			(net "GND")
		)
		(pad "6" smd rect
			(at 2.350008 0.32512)
			(size 0.4318 1.4986)
			(layers "F.Cu" "F.Mask" "F.Paste")
			(net "LTC4282_ALERT1_R_N")
		)
		(pad "7" smd rect
			(at 2.350008 -0.32512)
			(size 0.4318 1.4986)
			(layers "F.Cu" "F.Mask" "F.Paste")
			(net "SMB_LTC4282_TEMP_SDA")
		)
		(pad "8" smd rect
			(at 2.350008 -0.975106)
			(size 0.4318 1.4986)
			(layers "F.Cu" "F.Mask" "F.Paste")
			(net "SMB_LTC4282_TEMP_SCL")
		)
	)
	(footprint ""
		(layer "F.Cu")
		(at 146.538442 -252.356874 -90)
		(property "Reference" "R1289"
			(at 0 0 270)
			(layer "F.SilkS")
			(hide yes)
			(effects
				(font
					(size 1.27 1.27)
				)
			)
		)
		(property "Value" ""
			(at 0 0 270)
			(layer "F.Fab")
			(effects
				(font
					(size 1.27 1.27)
				)
			)
		)
		(duplicate_pad_numbers_are_jumpers no)
		(fp_line
			(start -0.7874 0.4064)
			(end -0.7874 -0.4064)
			(stroke
				(width 0.1524)
				(type default)
			)
			(layer "F.SilkS")
		)
		(fp_line
			(start 0.7874 0.4064)
			(end -0.7874 0.4064)
			(stroke
				(width 0.1524)
				(type default)
			)
			(layer "F.SilkS")
		)
		(fp_line
			(start -0.7874 -0.4064)
			(end 0.7874 -0.4064)
			(stroke
				(width 0.1524)
				(type default)
			)
			(layer "F.SilkS")
		)
		(fp_line
			(start 0.7874 -0.4064)
			(end 0.7874 0.4064)
			(stroke
				(width 0.1524)
				(type default)
			)
			(layer "F.SilkS")
		)
		(fp_line
			(start -0.67945 0.3048)
			(end -0.67945 -0.305054)
			(stroke
				(width 0.1)
				(type default)
			)
			(layer "F.Fab")
		)
		(fp_line
			(start -0.12065 0.3048)
			(end -0.67945 0.3048)
			(stroke
				(width 0.1)
				(type default)
			)
			(layer "F.Fab")
		)
		(fp_line
			(start 0.120396 0.3048)
			(end 0.120396 0.2794)
			(stroke
				(width 0.1)
				(type default)
			)
			(layer "F.Fab")
		)
		(fp_line
			(start 0.67945 0.3048)
			(end 0.120396 0.3048)
			(stroke
				(width 0.1)
				(type default)
			)
			(layer "F.Fab")
		)
		(fp_line
			(start -0.12065 0.2794)
			(end -0.12065 0.3048)
			(stroke
				(width 0.1)
				(type default)
			)
			(layer "F.Fab")
		)
		(fp_line
			(start 0.120396 0.2794)
			(end -0.12065 0.2794)
			(stroke
				(width 0.1)
				(type default)
			)
			(layer "F.Fab")
		)
		(fp_line
			(start -0.12065 -0.2794)
			(end 0.12065 -0.2794)
			(stroke
				(width 0.1)
				(type default)
			)
			(layer "F.Fab")
		)
		(fp_line
			(start 0.12065 -0.2794)
			(end 0.12065 -0.3048)
			(stroke
				(width 0.1)
				(type default)
			)
			(layer "F.Fab")
		)
		(fp_line
			(start 0.12065 -0.3048)
			(end 0.67945 -0.3048)
			(stroke
				(width 0.1)
				(type default)
			)
			(layer "F.Fab")
		)
		(fp_line
			(start 0.67945 -0.3048)
			(end 0.67945 0.3048)
			(stroke
				(width 0.1)
				(type default)
			)
			(layer "F.Fab")
		)
		(fp_line
			(start -0.67945 -0.305054)
			(end -0.12065 -0.305054)
			(stroke
				(width 0.1)
				(type default)
			)
			(layer "F.Fab")
		)
		(fp_line
			(start -0.12065 -0.305054)
			(end -0.12065 -0.2794)
			(stroke
				(width 0.1)
				(type default)
			)
			(layer "F.Fab")
		)
		(pad "1" smd circle
			(at -0.40005 0 270)
			(size 0 0)
			(layers "F.Cu" "F.Mask" "F.Paste")
			(net "GND")
		)
		(pad "2" smd circle
			(at 0.40005 0 270)
			(size 0 0)
			(layers "F.Cu" "F.Mask" "F.Paste")
			(net "PEX1_MODE_SEL0")
		)
	)
)
